# TIMECARD (Time Appliance Project (Time Card)) — schematic netlist excerpt (pin names and nets, part order shuffled) for the footprints in the layout excerpt that follows; sources: Cadence DE-HDL packaged netlist, KiCad conversion of R4006-B0001-02_R01.brd

R322  RESISTOR  33OHM 1%  pkg SMC_0402R_H016  page 26 : \1\ = FPGA_M_RGB_LED_I2C_SCL ; \2\ = R_RGB_LED_I2C_SCL
C44  CAPACITOR  0.1UF 25V 10%  pkg SMC_0402R_H022  page 32 : \1\ = UNNAMED_516_CAPACITOR_I27_1 ; \2\ = XP5R0V_SW

(kicad_pcb
	(version 20260206)
	(generator "pcbnew")
	(generator_version "10.0")
	(general
		(thickness 1.6)
		(legacy_teardrops no)
	)
	(paper "A4")
	(title_block
		(title "timecard-production-celestica-r4006 — R4006-B0001-02_R01.brd")
		(comment 1 "Time Appliance Project (Time Card) / footprints 1055-1056 of 1113")
	)
	(layers
		(0 "F.Cu" signal "TOP")
		(4 "In1.Cu" signal "L02_GND1")
		(6 "In2.Cu" signal "L03_SIG1")
		(8 "In3.Cu" signal "L04_GND2")
		(10 "In4.Cu" signal "L05_VCC1")
		(12 "In5.Cu" signal "L06_VCC2")
		(14 "In6.Cu" signal "L07_GND3")
		(16 "In7.Cu" signal "L08_SIG2")
		(18 "In8.Cu" signal "L09_GND4")
		(2 "B.Cu" signal "BOTTOM")
		(9 "F.Adhes" user "F.Adhesive")
		(11 "B.Adhes" user "B.Adhesive")
		(13 "F.Paste" user "Package Geometry/Pastemask Top")
		(15 "B.Paste" user "Package Geometry/Pastemask Bottom")
		(5 "F.SilkS" user "Ref Des/Silkscreen Top")
		(7 "B.SilkS" user "Ref Des/Silkscreen Bottom")
		(1 "F.Mask" user "Board Geometry/Soldermask Top")
		(3 "B.Mask" user "Board Geometry/Soldermask Bottom")
		(17 "Dwgs.User" user "User.Drawings")
		(19 "Cmts.User" user "User.Comments")
		(21 "Eco1.User" user "User.Eco1")
		(23 "Eco2.User" user "User.Eco2")
		(25 "Edge.Cuts" user "Board Geometry/Outline")
		(27 "Margin" user)
		(31 "F.CrtYd" user "Package Geometry/Place Bound Top")
		(29 "B.CrtYd" user "Package Geometry/Place Bound Bottom")
		(35 "F.Fab" user "Ref Des/Assembly Top")
		(33 "B.Fab" user "Ref Des/Assembly Bottom")
	)
	(footprint ""
		(layer "B.Cu")
		(at 111.125 -104.521)
		(property "Reference" "R322"
			(at 0.381 -3.00863 0)
			(unlocked yes)
			(layer "B.SilkS")
			(effects
				(font
					(size 0.7874 0.5842)
					(thickness 0.1524)
				)
				(justify mirror)
			)
		)
		(property "Value" "VAL*"
			(at -0.02032 2.13233 0)
			(unlocked yes)
			(layer "B.Fab")
			(hide yes)
			(effects
				(font
					(size 0.7874 0.5842)
					(thickness 0.1524)
				)
				(justify mirror)
			)
		)
		(property "Tolerance" "TOL*"
			(at -0.044704 3.05435 0)
			(unlocked yes)
			(layer "Cmts.User")
			(hide yes)
			(effects
				(font
					(size 0.7874 0.5842)
					(thickness 0.1524)
				)
				(justify mirror)
			)
		)
		(property "User Part Number" "PARTNUM*"
			(at -0.02032 4.024884 0)
			(unlocked yes)
			(layer "Cmts.User")
			(hide yes)
			(effects
				(font
					(size 0.7874 0.5842)
					(thickness 0.1524)
				)
				(justify mirror)
			)
		)
		(property "Device Type" "RESISTOR-G155-133R0-01,33OHM,1%"
			(at -0.008382 1.210564 0)
			(unlocked yes)
			(layer "B.Fab")
			(hide yes)
			(effects
				(font
					(size 0.7874 0.5842)
					(thickness 0.1524)
				)
				(justify mirror)
			)
		)
		(duplicate_pad_numbers_are_jumpers no)
		(fp_line
			(start -1.143 -0.5588)
			(end 1.143 -0.5588)
			(stroke
				(width 0.1)
				(type default)
			)
			(layer "B.SilkS")
		)
		(fp_line
			(start -1.143 0.5588)
			(end -1.143 -0.5588)
			(stroke
				(width 0.1)
				(type default)
			)
			(layer "B.SilkS")
		)
		(fp_line
			(start 1.143 -0.5588)
			(end 1.143 0.5588)
			(stroke
				(width 0.1)
				(type default)
			)
			(layer "B.SilkS")
		)
		(fp_line
			(start 1.143 0.5588)
			(end -1.143 0.5588)
			(stroke
				(width 0.1)
				(type default)
			)
			(layer "B.SilkS")
		)
		(fp_poly
			(pts
				(xy 1.143 0.5588) (xy -1.143 0.5588) (xy -1.143 -0.5588) (xy 1.143 -0.5588)
			)
			(stroke
				(width 0)
				(type default)
			)
			(fill no)
			(layer "B.CrtYd")
		)
		(fp_line
			(start -0.508 -0.3048)
			(end 0.508 -0.3048)
			(stroke
				(width 0.1)
				(type default)
			)
			(layer "B.Fab")
		)
		(fp_line
			(start -0.508 0.3048)
			(end -0.508 -0.3048)
			(stroke
				(width 0.1)
				(type default)
			)
			(layer "B.Fab")
		)
		(fp_line
			(start 0.508 -0.3048)
			(end 0.508 0.3048)
			(stroke
				(width 0.1)
				(type default)
			)
			(layer "B.Fab")
		)
		(fp_line
			(start 0.508 0.3048)
			(end -0.508 0.3048)
			(stroke
				(width 0.1)
				(type default)
			)
			(layer "B.Fab")
		)
		(pad "1" smd rect
			(at 0.5334 0 180)
			(size 0.7112 0.6096)
			(layers "B.Cu" "B.Mask" "B.Paste")
			(net "FPGA_M_RGB_LED_I2C_SCL")
		)
		(pad "2" smd rect
			(at -0.5334 0 180)
			(size 0.7112 0.6096)
			(layers "B.Cu" "B.Mask" "B.Paste")
			(net "R_RGB_LED_I2C_SCL")
		)
		(zone
			(layer "B.Cu")
			(hatch none 0.5)
			(connect_pads
				(clearance 0)
			)
			(min_thickness 0.25)
			(keepout
				(tracks not_allowed)
				(vias allowed)
				(pads allowed)
				(copperpour not_allowed)
				(footprints allowed)
			)
			(placement
				(enabled no)
				(sheetname "")
			)
			(fill
				(thermal_gap 0.5)
				(thermal_bridge_width 0.5)
				(island_removal_mode 0)
			)
			(polygon
				(pts
					(xy 111.2012 -104.2162) (xy 111.2012 -104.8258) (xy 111.0488 -104.8258) (xy 111.0488 -104.2162)
				)
			)
		)
		(zone
			(layer "B.Cu")
			(hatch none 0.5)
			(connect_pads
				(clearance 0)
			)
			(min_thickness 0.25)
			(keepout
				(tracks allowed)
				(vias not_allowed)
				(pads allowed)
				(copperpour not_allowed)
				(footprints allowed)
			)
			(placement
				(enabled no)
				(sheetname "")
			)
			(fill
				(thermal_gap 0.5)
				(thermal_bridge_width 0.5)
				(island_removal_mode 0)
			)
			(polygon
				(pts
					(xy 111.2012 -104.2162) (xy 111.2012 -104.8258) (xy 111.0488 -104.8258) (xy 111.0488 -104.2162)
				)
			)
		)
	)
	(footprint ""
		(layer "B.Cu")
		(at 44.323 -99.314 180)
		(property "Reference" "C44"
			(at -2.4384 -0.03937 0)
			(unlocked yes)
			(layer "B.SilkS")
			(effects
				(font
					(size 0.7874 0.5842)
					(thickness 0.1524)
				)
				(justify mirror)
			)
		)
		(property "Value" "VAL*"
			(at -0.0762 2.067306 180)
			(unlocked yes)
			(layer "B.Fab")
			(hide yes)
			(effects
				(font
					(size 0.7874 0.5842)
					(thickness 0.1524)
				)
				(justify mirror)
			)
		)
		(property "Tolerance" "TOL*"
			(at -0.0762 3.032506 180)
			(unlocked yes)
			(layer "Cmts.User")
			(hide yes)
			(effects
				(font
					(size 0.7874 0.5842)
					(thickness 0.1524)
				)
				(justify mirror)
			)
		)
		(property "User Part Number" "PARTNUM*"
			(at -0.1016 4.023106 180)
			(unlocked yes)
			(layer "Cmts.User")
			(hide yes)
			(effects
				(font
					(size 0.7874 0.5842)
					(thickness 0.1524)
				)
				(justify mirror)
			)
		)
		(property "Device Type" "CAPACITOR-G105-0B104-EK,0.1UF,A"
			(at -0.0508 1.127506 180)
			(unlocked yes)
			(layer "B.Fab")
			(hide yes)
			(effects
				(font
					(size 0.7874 0.5842)
					(thickness 0.1524)
				)
				(justify mirror)
			)
		)
		(duplicate_pad_numbers_are_jumpers no)
		(fp_line
			(start 1.143 0.5588)
			(end -1.143 0.5588)
			(stroke
				(width 0.1)
				(type default)
			)
			(layer "B.SilkS")
		)
		(fp_line
			(start 1.143 -0.5588)
			(end 1.143 0.5588)
			(stroke
				(width 0.1)
				(type default)
			)
			(layer "B.SilkS")
		)
		(fp_line
			(start -1.143 0.5588)
			(end -1.143 -0.5588)
			(stroke
				(width 0.1)
				(type default)
			)
			(layer "B.SilkS")
		)
		(fp_line
			(start -1.143 -0.5588)
			(end 1.143 -0.5588)
			(stroke
				(width 0.1)
				(type default)
			)
			(layer "B.SilkS")
		)
		(fp_rect
			(start 1.143 0.5588)
			(end -1.143 -0.5588)
			(stroke
				(width 0)
				(type default)
			)
			(fill no)
			(layer "B.CrtYd")
		)
		(fp_line
			(start 0.508 0.3048)
			(end -0.508 0.3048)
			(stroke
				(width 0.1)
				(type default)
			)
			(layer "B.Fab")
		)
		(fp_line
			(start 0.508 -0.3048)
			(end 0.508 0.3048)
			(stroke
				(width 0.1)
				(type default)
			)
			(layer "B.Fab")
		)
		(fp_line
			(start -0.508 0.3048)
			(end -0.508 -0.3048)
			(stroke
				(width 0.1)
				(type default)
			)
			(layer "B.Fab")
		)
		(fp_line
			(start -0.508 -0.3048)
			(end 0.508 -0.3048)
			(stroke
				(width 0.1)
				(type default)
			)
			(layer "B.Fab")
		)
		(pad "1" smd rect
			(at 0.5334 0)
			(size 0.7112 0.6096)
			(layers "B.Cu" "B.Mask" "B.Paste")
			(net "UNNAMED_516_CAPACITOR_I27_1")
		)
		(pad "2" smd rect
			(at -0.5334 0)
			(size 0.7112 0.6096)
			(layers "B.Cu" "B.Mask" "B.Paste")
			(net "XP5R0V_SW")
		)
		(zone
			(layer "B.Cu")
			(hatch none 0.5)
			(connect_pads
				(clearance 0)
			)
			(min_thickness 0.25)
			(keepout
				(tracks allowed)
				(vias not_allowed)
				(pads allowed)
				(copperpour not_allowed)
				(footprints allowed)
			)
			(placement
				(enabled no)
				(sheetname "")
			)
			(fill
				(thermal_gap 0.5)
				(thermal_bridge_width 0.5)
				(island_removal_mode 0)
			)
			(polygon
				(pts
					(xy 44.2468 -99.6188) (xy 44.2468 -99.0092) (xy 44.3992 -99.0092) (xy 44.3992 -99.6188)
				)
			)
		)
	)
)
